# S9S_MB_2U (Grand Teton) — schematic netlist excerpt (pin names and nets, part order shuffled) for the footprints in the layout excerpt that follows; sources: Cadence DE-HDL packaged netlist, KiCad conversion of 03242023_DA0F0TMBIJ0_F0T_Motherboard_J_brd_V01_OCP.brd

R2977  Q_RES  1K 1% CHIP  pkg 0402LF  page 195 : A = FM_BOARD_SKU_ID3 ; B = GND
R3194  Q_RES  22 1% CHIP  pkg 0402LF  page 207 : A = CLK_100M_OCP_V3_2_A_R_DP ; B = CLK_100M_OCP_V3_2_A_DP

(kicad_pcb
	(version 20260206)
	(generator "pcbnew")
	(generator_version "10.0")
	(general
		(thickness 1.6)
		(legacy_teardrops no)
	)
	(paper "A4")
	(title_block
		(title "03242023_DA0F0TMBIJ0_F0T_Motherboard_J_brd_V01_OCP.brd")
		(comment 1 "Grand Teton / footprints 748-749 of 6105")
	)
	(layers
		(0 "F.Cu" signal "TOP")
		(4 "In1.Cu" signal "GND")
		(6 "In2.Cu" signal "IN1")
		(8 "In3.Cu" signal "GND1")
		(10 "In4.Cu" signal "IN2")
		(12 "In5.Cu" signal "GND2")
		(14 "In6.Cu" signal "IN3")
		(16 "In7.Cu" signal "GND3")
		(18 "In8.Cu" signal "VCC")
		(20 "In9.Cu" signal "VCC1")
		(22 "In10.Cu" signal "GND4")
		(24 "In11.Cu" signal "IN4")
		(26 "In12.Cu" signal "GND5")
		(28 "In13.Cu" signal "IN5")
		(30 "In14.Cu" signal "GND6")
		(32 "In15.Cu" signal "IN6")
		(34 "In16.Cu" signal "GND7")
		(2 "B.Cu" signal "BOTTOM")
		(9 "F.Adhes" user "F.Adhesive")
		(11 "B.Adhes" user "B.Adhesive")
		(13 "F.Paste" user "Package Geometry/Pastemask Top")
		(15 "B.Paste" user "Package Geometry/Pastemask Bottom")
		(5 "F.SilkS" user "Ref Des/Silkscreen Top")
		(7 "B.SilkS" user "Ref Des/Silkscreen Bottom")
		(1 "F.Mask" user "Board Geometry/Soldermask Top")
		(3 "B.Mask" user "Board Geometry/Soldermask Bottom")
		(17 "Dwgs.User" user "User.Drawings")
		(19 "Cmts.User" user "User.Comments")
		(21 "Eco1.User" user "User.Eco1")
		(23 "Eco2.User" user "User.Eco2")
		(25 "Edge.Cuts" user "Board Geometry/Outline")
		(27 "Margin" user)
		(31 "F.CrtYd" user "Package Geometry/Place Bound Top")
		(29 "B.CrtYd" user "Package Geometry/Place Bound Bottom")
		(35 "F.Fab" user "Ref Des/Assembly Top")
		(33 "B.Fab" user "Ref Des/Assembly Bottom")
	)
	(footprint ""
		(layer "F.Cu")
		(at 299.02023 -53.384196 180)
		(property "Reference" "R2977"
			(at 0 0 180)
			(layer "F.SilkS")
			(hide yes)
			(effects
				(font
					(size 1.27 1.27)
				)
			)
		)
		(property "Value" ""
			(at 0 0 180)
			(layer "F.Fab")
			(effects
				(font
					(size 1.27 1.27)
				)
			)
		)
		(duplicate_pad_numbers_are_jumpers no)
		(fp_line
			(start 0.7874 0.4064)
			(end -0.7874 0.4064)
			(stroke
				(width 0.1524)
				(type default)
			)
			(layer "F.SilkS")
		)
		(fp_line
			(start 0.7874 -0.4064)
			(end 0.7874 0.4064)
			(stroke
				(width 0.1524)
				(type default)
			)
			(layer "F.SilkS")
		)
		(fp_line
			(start -0.7874 0.4064)
			(end -0.7874 -0.4064)
			(stroke
				(width 0.1524)
				(type default)
			)
			(layer "F.SilkS")
		)
		(fp_line
			(start -0.7874 -0.4064)
			(end 0.7874 -0.4064)
			(stroke
				(width 0.1524)
				(type default)
			)
			(layer "F.SilkS")
		)
		(fp_line
			(start 0.67945 0.3048)
			(end 0.120396 0.3048)
			(stroke
				(width 0.1)
				(type default)
			)
			(layer "F.Fab")
		)
		(fp_line
			(start 0.67945 -0.3048)
			(end 0.67945 0.3048)
			(stroke
				(width 0.1)
				(type default)
			)
			(layer "F.Fab")
		)
		(fp_line
			(start 0.12065 -0.2794)
			(end 0.12065 -0.3048)
			(stroke
				(width 0.1)
				(type default)
			)
			(layer "F.Fab")
		)
		(fp_line
			(start 0.12065 -0.3048)
			(end 0.67945 -0.3048)
			(stroke
				(width 0.1)
				(type default)
			)
			(layer "F.Fab")
		)
		(fp_line
			(start 0.120396 0.3048)
			(end 0.120396 0.2794)
			(stroke
				(width 0.1)
				(type default)
			)
			(layer "F.Fab")
		)
		(fp_line
			(start 0.120396 0.2794)
			(end -0.12065 0.2794)
			(stroke
				(width 0.1)
				(type default)
			)
			(layer "F.Fab")
		)
		(fp_line
			(start -0.12065 0.3048)
			(end -0.67945 0.3048)
			(stroke
				(width 0.1)
				(type default)
			)
			(layer "F.Fab")
		)
		(fp_line
			(start -0.12065 0.2794)
			(end -0.12065 0.3048)
			(stroke
				(width 0.1)
				(type default)
			)
			(layer "F.Fab")
		)
		(fp_line
			(start -0.12065 -0.2794)
			(end 0.12065 -0.2794)
			(stroke
				(width 0.1)
				(type default)
			)
			(layer "F.Fab")
		)
		(fp_line
			(start -0.12065 -0.305054)
			(end -0.12065 -0.2794)
			(stroke
				(width 0.1)
				(type default)
			)
			(layer "F.Fab")
		)
		(fp_line
			(start -0.67945 0.3048)
			(end -0.67945 -0.305054)
			(stroke
				(width 0.1)
				(type default)
			)
			(layer "F.Fab")
		)
		(fp_line
			(start -0.67945 -0.305054)
			(end -0.12065 -0.305054)
			(stroke
				(width 0.1)
				(type default)
			)
			(layer "F.Fab")
		)
		(pad "1" smd circle
			(at -0.40005 0 180)
			(size 0 0)
			(layers "F.Cu" "F.Mask" "F.Paste")
			(net "FM_BOARD_SKU_ID3")
		)
		(pad "2" smd circle
			(at 0.40005 0 180)
			(size 0 0)
			(layers "F.Cu" "F.Mask" "F.Paste")
			(net "GND")
		)
	)
	(footprint ""
		(layer "F.Cu")
		(at 233.869738 -119.183658 -90)
		(property "Reference" "R3194"
			(at 0 0 270)
			(layer "F.SilkS")
			(hide yes)
			(effects
				(font
					(size 1.27 1.27)
				)
			)
		)
		(property "Value" ""
			(at 0 0 270)
			(layer "F.Fab")
			(effects
				(font
					(size 1.27 1.27)
				)
			)
		)
		(duplicate_pad_numbers_are_jumpers no)
		(fp_line
			(start -0.7874 0.4064)
			(end -0.7874 -0.109982)
			(stroke
				(width 0.1524)
				(type default)
			)
			(layer "F.SilkS")
		)
		(fp_line
			(start 0.7874 0.4064)
			(end -0.7874 0.4064)
			(stroke
				(width 0.1524)
				(type default)
			)
			(layer "F.SilkS")
		)
		(fp_line
			(start 0.7874 -0.089662)
			(end 0.7874 0.4064)
			(stroke
				(width 0.1524)
				(type default)
			)
			(layer "F.SilkS")
		)
		(fp_line
			(start -0.363982 -0.4064)
			(end 0.410718 -0.4064)
			(stroke
				(width 0.1524)
				(type default)
			)
			(layer "F.SilkS")
		)
		(fp_line
			(start -0.67945 0.3048)
			(end -0.67945 -0.305054)
			(stroke
				(width 0.1)
				(type default)
			)
			(layer "F.Fab")
		)
		(fp_line
			(start -0.12065 0.3048)
			(end -0.67945 0.3048)
			(stroke
				(width 0.1)
				(type default)
			)
			(layer "F.Fab")
		)
		(fp_line
			(start 0.120396 0.3048)
			(end 0.120396 0.2794)
			(stroke
				(width 0.1)
				(type default)
			)
			(layer "F.Fab")
		)
		(fp_line
			(start 0.67945 0.3048)
			(end 0.120396 0.3048)
			(stroke
				(width 0.1)
				(type default)
			)
			(layer "F.Fab")
		)
		(fp_line
			(start -0.12065 0.2794)
			(end -0.12065 0.3048)
			(stroke
				(width 0.1)
				(type default)
			)
			(layer "F.Fab")
		)
		(fp_line
			(start 0.120396 0.2794)
			(end -0.12065 0.2794)
			(stroke
				(width 0.1)
				(type default)
			)
			(layer "F.Fab")
		)
		(fp_line
			(start -0.12065 -0.2794)
			(end 0.12065 -0.2794)
			(stroke
				(width 0.1)
				(type default)
			)
			(layer "F.Fab")
		)
		(fp_line
			(start 0.12065 -0.2794)
			(end 0.12065 -0.3048)
			(stroke
				(width 0.1)
				(type default)
			)
			(layer "F.Fab")
		)
		(fp_line
			(start 0.12065 -0.3048)
			(end 0.67945 -0.3048)
			(stroke
				(width 0.1)
				(type default)
			)
			(layer "F.Fab")
		)
		(fp_line
			(start 0.67945 -0.3048)
			(end 0.67945 0.3048)
			(stroke
				(width 0.1)
				(type default)
			)
			(layer "F.Fab")
		)
		(fp_line
			(start -0.67945 -0.305054)
			(end -0.12065 -0.305054)
			(stroke
				(width 0.1)
				(type default)
			)
			(layer "F.Fab")
		)
		(fp_line
			(start -0.12065 -0.305054)
			(end -0.12065 -0.2794)
			(stroke
				(width 0.1)
				(type default)
			)
			(layer "F.Fab")
		)
		(pad "1" smd circle
			(at -0.40005 0 270)
			(size 0 0)
			(layers "F.Cu" "F.Mask" "F.Paste")
			(net "CLK_100M_OCP_V3_2_A_R_DP")
		)
		(pad "2" smd circle
			(at 0.40005 0 270)
			(size 0 0)
			(layers "F.Cu" "F.Mask" "F.Paste")
			(net "CLK_100M_OCP_V3_2_A_DP")
		)
	)
)
